G04 ================== begin FILE IDENTIFICATION RECORD ==================*
G04 Layout Name:  t6m_pdb_d_0928_1400_274.brd*
G04 Film Name:    pmb*
G04 File Format:  Gerber RS274X*
G04 File Origin:  Cadence Allegro 16.3-S048*
G04 Origin Date:  Tue Nov 26 11:01:52 2013*
G04 *
G04 Layer:  VIA CLASS/PASTEMASK_BOTTOM*
G04 Layer:  PIN/PASTEMASK_BOTTOM*
G04 Layer:  PACKAGE GEOMETRY/PASTEMASK_BOTTOM*
G04 Layer:  MANUFACTURING/PHOTOPLOT_OUTLINE*
G04 Layer:  DRAWING FORMAT/TITLE_BLOCK*
G04 Layer:  DRAWING FORMAT/TITLE_DATA_PMB*
G04 *
G04 Offset:    (0.00 0.00)*
G04 Mirror:    No*
G04 Mode:      Positive*
G04 Rotation:  0*
G04 FullContactRelief:  No*
G04 UndefLineWidth:     6.00*
G04 ================== end FILE IDENTIFICATION RECORD ====================*
%FSLAX25Y25*MOIN*%
%IR0*IPPOS*OFA0.00000B0.00000*MIA0B0*SFA1.00000B1.00000*%
%ADD20C,.03*%
%ADD14C,.06*%
%ADD12C,.052*%
%ADD18C,.026*%
%ADD22C,.064*%
%ADD10C,.055*%
%ADD21C,.039*%
%ADD13C,.093*%
%ADD15R,.06X.06*%
%ADD17C,.077*%
%ADD16R,.052X.052*%
%ADD23R,.064X.064*%
%ADD11R,.055X.055*%
%ADD19R,.077X.077*%
%ADD24C,.006*%
G75*
%LPD*%
G75*
G54D10*
X17735Y24953D03*
X27735D03*
X22735Y34953D03*
Y216976D03*
X27735Y206976D03*
X17735Y233811D03*
X27735D03*
X22735Y243811D03*
X27735Y415834D03*
X22735Y425834D03*
Y1957291D03*
X27735Y1947291D03*
X22735Y2061661D03*
X27735Y2051661D03*
X37735Y24953D03*
X47735D03*
X32735Y34953D03*
X42735D03*
Y216976D03*
X32735D03*
X47735Y206976D03*
X37735D03*
Y233811D03*
X47735D03*
X32735Y243811D03*
X42735D03*
X47735Y415834D03*
X37735D03*
X42735Y425834D03*
X32735D03*
X42735Y1957291D03*
X32735D03*
X47735Y1947291D03*
X37735D03*
X42735Y2061661D03*
X32735D03*
X47735Y2051661D03*
X37735D03*
X52735Y216976D03*
Y425834D03*
Y1957291D03*
Y2061661D03*
X189762Y73105D03*
X190289Y152050D03*
X190357Y247568D03*
X190817Y331786D03*
X189761Y421732D03*
X190553Y506517D03*
X192888Y598130D03*
X190816Y681645D03*
X191846Y774526D03*
X191606Y856244D03*
X196311Y947202D03*
X195516Y1032544D03*
X191250Y1122856D03*
X191342Y1206233D03*
X191846Y1299104D03*
X190552Y1380966D03*
X189463Y1474162D03*
X191079Y1557277D03*
X192143Y1648177D03*
X191607Y1731351D03*
X191530Y1823227D03*
X190289Y1900420D03*
X192125Y1998730D03*
X191530Y2043388D03*
G54D11*
X17735Y206976D03*
Y415834D03*
Y1947291D03*
Y2051661D03*
X52735Y34953D03*
Y243811D03*
X203542Y73105D03*
X204069Y152050D03*
X204137Y247568D03*
X204597Y331786D03*
X203541Y421732D03*
X204333Y506517D03*
X206668Y598130D03*
X204596Y681645D03*
X205626Y774526D03*
X205386Y856244D03*
X210091Y947202D03*
X209296Y1032544D03*
X205030Y1122856D03*
X205122Y1206233D03*
X205626Y1299104D03*
X204332Y1380966D03*
X203243Y1474162D03*
X204859Y1557277D03*
X205923Y1648177D03*
X205387Y1731351D03*
X205310Y1823227D03*
X204069Y1900420D03*
X205905Y1998730D03*
X205310Y2043388D03*
G54D20*
X65354Y101180D03*
X55511Y105117D03*
X51574Y114960D03*
X55511Y124803D03*
X65354Y128740D03*
Y451180D03*
X55511Y455117D03*
X51574Y464960D03*
X55511Y474803D03*
X65354Y478740D03*
Y801180D03*
X55511Y805117D03*
X51574Y814960D03*
X55511Y824803D03*
X65354Y828740D03*
Y1151180D03*
X55511Y1155117D03*
X51574Y1164960D03*
X55511Y1174803D03*
X65354Y1178740D03*
Y1501180D03*
X55511Y1505117D03*
X51574Y1514960D03*
X55511Y1524803D03*
X65354Y1528740D03*
Y1851180D03*
X55511Y1855117D03*
X51574Y1864960D03*
X55511Y1874803D03*
X65354Y1878740D03*
X75197Y105117D03*
Y124803D03*
X79134Y114960D03*
Y464960D03*
X75197Y455117D03*
Y474803D03*
Y805117D03*
Y824803D03*
X79134Y814960D03*
Y1164960D03*
X75197Y1155117D03*
Y1174803D03*
Y1505117D03*
Y1524803D03*
X79134Y1514960D03*
Y1864960D03*
X75197Y1855117D03*
Y1874803D03*
X307086Y113385D03*
X297243Y117322D03*
X293306Y127165D03*
X297243Y137008D03*
X307086Y140945D03*
Y463385D03*
X297243Y467322D03*
X293306Y477165D03*
X297243Y487008D03*
X307086Y490945D03*
Y813385D03*
X297243Y817322D03*
X293306Y827165D03*
X297243Y837008D03*
X307086Y840945D03*
Y1329724D03*
X297243Y1333661D03*
X293306Y1343504D03*
X297243Y1353347D03*
X307086Y1357284D03*
Y1679724D03*
X297243Y1683661D03*
X293306Y1693504D03*
X297243Y1703347D03*
X307086Y1707284D03*
X307087Y2029723D03*
X297244Y2033660D03*
X293307Y2043503D03*
X297244Y2053346D03*
X307087Y2057283D03*
X320866Y127165D03*
X316929Y117322D03*
Y137008D03*
Y467322D03*
Y487008D03*
X320866Y477165D03*
Y827165D03*
X316929Y817322D03*
Y837008D03*
Y1333661D03*
Y1353347D03*
X320866Y1343504D03*
Y1693504D03*
X316929Y1683661D03*
Y1703347D03*
X316930Y2033660D03*
Y2053346D03*
X320867Y2043503D03*
G54D21*
X55158Y882277D03*
X344826Y2035270D03*
X389572Y66182D03*
G54D12*
X18995Y508701D03*
X23995Y518701D03*
X21495Y559882D03*
X11692D03*
X21495Y1571811D03*
X11692D03*
X23995Y1622992D03*
X28995Y508701D03*
X38995D03*
X48995D03*
X33995Y518701D03*
X43995D03*
X51495Y559882D03*
Y1571811D03*
X43995Y1622992D03*
X33995D03*
X48995Y1612992D03*
X38995D03*
X28995D03*
X61298Y559882D03*
Y1571811D03*
X53995Y1622992D03*
G54D13*
X5491Y528544D03*
Y1603149D03*
X67499Y528544D03*
Y1603149D03*
G54D22*
X119920Y18071D03*
Y28071D03*
Y38071D03*
Y48071D03*
Y58071D03*
Y68071D03*
Y78071D03*
Y88071D03*
Y98071D03*
Y108071D03*
Y118071D03*
Y128071D03*
Y138071D03*
Y148071D03*
Y158071D03*
Y168071D03*
Y178071D03*
Y188071D03*
Y198071D03*
Y208071D03*
Y218071D03*
Y228071D03*
Y238071D03*
Y248071D03*
Y258071D03*
Y268071D03*
Y278071D03*
Y288071D03*
Y298071D03*
Y308071D03*
Y318071D03*
Y366102D03*
Y376102D03*
Y386102D03*
Y396102D03*
Y406102D03*
Y416102D03*
Y426102D03*
Y436102D03*
Y446102D03*
Y456102D03*
Y466102D03*
Y476102D03*
Y486102D03*
Y496102D03*
Y506102D03*
Y516102D03*
Y526102D03*
Y536102D03*
Y546102D03*
Y556102D03*
Y566102D03*
Y576102D03*
Y586102D03*
Y596102D03*
Y606102D03*
Y616102D03*
Y626102D03*
Y636102D03*
Y646102D03*
Y656102D03*
Y666102D03*
Y714134D03*
Y724134D03*
Y734134D03*
Y744134D03*
Y754134D03*
Y764134D03*
Y774134D03*
Y784134D03*
Y794134D03*
Y804134D03*
Y814134D03*
Y824134D03*
Y834134D03*
Y844134D03*
Y854134D03*
Y864134D03*
Y874134D03*
Y884134D03*
Y894134D03*
Y904134D03*
Y914134D03*
Y924134D03*
Y934134D03*
Y944134D03*
Y954134D03*
Y964134D03*
Y974134D03*
Y984134D03*
Y994134D03*
Y1004134D03*
Y1014134D03*
Y1062165D03*
Y1072165D03*
Y1082165D03*
Y1092165D03*
Y1102165D03*
Y1112165D03*
Y1122165D03*
Y1132165D03*
Y1142165D03*
Y1152165D03*
Y1162165D03*
Y1172165D03*
Y1182165D03*
Y1192165D03*
Y1202165D03*
Y1212165D03*
Y1222165D03*
Y1232165D03*
Y1242165D03*
Y1252165D03*
Y1262165D03*
Y1272165D03*
Y1282165D03*
Y1292165D03*
Y1302165D03*
Y1312165D03*
Y1322165D03*
Y1332165D03*
Y1342165D03*
Y1352165D03*
Y1362165D03*
Y1410197D03*
Y1420197D03*
Y1430197D03*
Y1440197D03*
Y1450197D03*
Y1460197D03*
Y1470197D03*
Y1480197D03*
Y1490197D03*
Y1500197D03*
Y1510197D03*
Y1520197D03*
Y1530197D03*
Y1540197D03*
Y1550197D03*
Y1560197D03*
Y1570197D03*
Y1580197D03*
Y1590197D03*
Y1600197D03*
Y1610197D03*
Y1620197D03*
Y1630197D03*
Y1640197D03*
Y1650197D03*
Y1660197D03*
Y1670197D03*
Y1680197D03*
Y1690197D03*
Y1700197D03*
Y1710197D03*
Y1758228D03*
Y1768228D03*
Y1778228D03*
Y1788228D03*
Y1798228D03*
Y1808228D03*
Y1818228D03*
Y1828228D03*
Y1838228D03*
Y1848228D03*
Y1858228D03*
Y1868228D03*
Y1878228D03*
Y1888228D03*
Y1898228D03*
Y1908228D03*
Y1918228D03*
Y1928228D03*
Y1938228D03*
Y1948228D03*
Y1958228D03*
Y1968228D03*
Y1978228D03*
Y1988228D03*
Y1998228D03*
Y2008228D03*
Y2018228D03*
Y2028228D03*
Y2038228D03*
Y2048228D03*
Y2058228D03*
X139920Y28071D03*
Y18071D03*
Y58071D03*
Y48071D03*
Y38071D03*
Y78071D03*
Y68071D03*
Y98071D03*
Y88071D03*
Y128071D03*
Y118071D03*
Y108071D03*
Y148071D03*
Y138071D03*
Y178071D03*
Y168071D03*
Y158071D03*
Y198071D03*
Y188071D03*
Y228071D03*
Y218071D03*
Y208071D03*
Y248071D03*
Y238071D03*
Y268071D03*
Y258071D03*
Y298071D03*
Y288071D03*
Y278071D03*
Y318071D03*
Y308071D03*
Y328071D03*
Y366102D03*
Y396102D03*
Y386102D03*
Y376102D03*
Y416102D03*
Y406102D03*
Y436102D03*
Y426102D03*
Y466102D03*
Y456102D03*
Y446102D03*
Y486102D03*
Y476102D03*
Y516102D03*
Y506102D03*
Y496102D03*
Y536102D03*
Y526102D03*
Y566102D03*
Y556102D03*
Y546102D03*
Y586102D03*
Y576102D03*
Y606102D03*
Y596102D03*
Y636102D03*
Y626102D03*
Y616102D03*
Y656102D03*
Y646102D03*
Y676102D03*
Y666102D03*
Y734134D03*
Y724134D03*
Y714134D03*
Y754134D03*
Y744134D03*
Y774134D03*
Y764134D03*
Y804134D03*
Y794134D03*
Y784134D03*
Y824134D03*
Y814134D03*
Y854134D03*
Y844134D03*
Y834134D03*
Y874134D03*
Y864134D03*
Y904134D03*
Y894134D03*
Y884134D03*
Y924134D03*
Y914134D03*
Y944134D03*
Y934134D03*
Y974134D03*
Y964134D03*
Y954134D03*
Y994134D03*
Y984134D03*
Y1024134D03*
Y1014134D03*
Y1004134D03*
Y1072165D03*
Y1062165D03*
Y1092165D03*
Y1082165D03*
Y1122165D03*
Y1112165D03*
Y1102165D03*
Y1142165D03*
Y1132165D03*
Y1162165D03*
Y1152165D03*
Y1192165D03*
Y1182165D03*
Y1172165D03*
Y1212165D03*
Y1202165D03*
Y1242165D03*
Y1232165D03*
Y1222165D03*
Y1262165D03*
Y1252165D03*
Y1282165D03*
Y1272165D03*
Y1312165D03*
Y1302165D03*
Y1292165D03*
Y1332165D03*
Y1322165D03*
Y1362165D03*
Y1352165D03*
Y1342165D03*
Y1372165D03*
Y1410197D03*
Y1430197D03*
Y1420197D03*
Y1460197D03*
Y1450197D03*
Y1440197D03*
Y1480197D03*
Y1470197D03*
Y1500197D03*
Y1490197D03*
Y1530197D03*
Y1520197D03*
Y1510197D03*
Y1550197D03*
Y1540197D03*
Y1580197D03*
Y1570197D03*
Y1560197D03*
Y1600197D03*
Y1590197D03*
Y1620197D03*
Y1610197D03*
Y1650197D03*
Y1640197D03*
Y1630197D03*
Y1670197D03*
Y1660197D03*
Y1700197D03*
Y1690197D03*
Y1680197D03*
Y1720197D03*
Y1710197D03*
Y1768228D03*
Y1758228D03*
Y1798228D03*
Y1788228D03*
Y1778228D03*
Y1818228D03*
Y1808228D03*
Y1838228D03*
Y1828228D03*
Y1868228D03*
Y1858228D03*
Y1848228D03*
Y1888228D03*
Y1878228D03*
Y1918228D03*
Y1908228D03*
Y1898228D03*
Y1938228D03*
Y1928228D03*
Y1958228D03*
Y1948228D03*
Y1988228D03*
Y1978228D03*
Y1968228D03*
Y2008228D03*
Y1998228D03*
Y2038228D03*
Y2028228D03*
Y2018228D03*
Y2058228D03*
Y2048228D03*
Y2068228D03*
G54D23*
X119920Y328071D03*
Y676102D03*
Y1024134D03*
Y1372165D03*
Y1720197D03*
Y2068228D03*
G54D14*
X17480Y599901D03*
Y627264D03*
Y1471949D03*
Y1499311D03*
G54D24*
G01X-723776Y2987387D02*
Y-376795D01*
Y-489221D01*
X1782976D01*
Y-376795D01*
Y2987387D01*
X-723776D01*
G01X-4000Y-62500D02*
Y-137500D01*
X496000D01*
Y-62500D01*
X-4000D01*
G01X8000Y-127500D02*
Y-132500D01*
G01X6543Y-127500D02*
X9457D01*
G01X14367Y-132500D02*
X11833D01*
Y-127500D01*
X14367D01*
G01X13353Y-129917D02*
X11833D01*
G01X16933Y-127500D02*
Y-132500D01*
X19467D01*
G01X23300Y-132667D02*
X23173Y-132583D01*
Y-132417D01*
X23300Y-132333D01*
X23427Y-132417D01*
Y-132583D01*
X23300Y-132667D01*
G01Y-130417D02*
X23173Y-130333D01*
Y-130167D01*
X23300Y-130083D01*
X23427Y-130167D01*
Y-130333D01*
X23300Y-130417D01*
G01X28083Y-134167D02*
X27450Y-133333D01*
X27133Y-132500D01*
Y-129167D01*
X27450Y-128333D01*
X28083Y-127500D01*
G01X33500D02*
X32993Y-127667D01*
X32613Y-128083D01*
X32360Y-128583D01*
X32170Y-129250D01*
X32107Y-130000D01*
X32170Y-130750D01*
X32360Y-131417D01*
X32613Y-131917D01*
X32993Y-132333D01*
X33500Y-132500D01*
X34007Y-132333D01*
X34387Y-131917D01*
X34640Y-131417D01*
X34830Y-130750D01*
X34893Y-130000D01*
X34830Y-129250D01*
X34640Y-128583D01*
X34387Y-128083D01*
X34007Y-127667D01*
X33500Y-127500D01*
G01X37207Y-131500D02*
X37587Y-132083D01*
X38093Y-132417D01*
X38663Y-132500D01*
X39170Y-132417D01*
X39677Y-132000D01*
X39993Y-131500D01*
X40057Y-131000D01*
X39930Y-130417D01*
X39487Y-130000D01*
X39043Y-129833D01*
X38473D01*
G01X39043D02*
X39423Y-129583D01*
X39740Y-129167D01*
X39867Y-128667D01*
X39740Y-128167D01*
X39423Y-127750D01*
X38853Y-127500D01*
X38283Y-127583D01*
X37713Y-127917D01*
G01X44017Y-134167D02*
X44650Y-133333D01*
X44967Y-132500D01*
Y-129167D01*
X44650Y-128333D01*
X44017Y-127500D01*
G01X47407Y-131500D02*
X47787Y-132083D01*
X48293Y-132417D01*
X48863Y-132500D01*
X49370Y-132417D01*
X49877Y-132000D01*
X50193Y-131500D01*
X50257Y-131000D01*
X50130Y-130417D01*
X49687Y-130000D01*
X49243Y-129833D01*
X48673D01*
G01X49243D02*
X49623Y-129583D01*
X49940Y-129167D01*
X50067Y-128667D01*
X49940Y-128167D01*
X49623Y-127750D01*
X49053Y-127500D01*
X48483Y-127583D01*
X47913Y-127917D01*
G01X52697Y-128333D02*
X53077Y-127833D01*
X53520Y-127583D01*
X54027Y-127500D01*
X54660Y-127667D01*
X55103Y-128083D01*
X55230Y-128583D01*
X55167Y-129083D01*
X54913Y-129500D01*
X53647Y-130333D01*
X53077Y-130917D01*
X52697Y-131750D01*
X52570Y-132500D01*
X55230D01*
G01X58873D02*
X59000Y-131417D01*
X59190Y-130500D01*
X59443Y-129667D01*
X59760Y-128750D01*
X60267Y-127500D01*
X57733D01*
G01X63277Y-130833D02*
X64923D01*
G01X67997Y-128333D02*
X68377Y-127833D01*
X68820Y-127583D01*
X69327Y-127500D01*
X69960Y-127667D01*
X70403Y-128083D01*
X70530Y-128583D01*
X70467Y-129083D01*
X70213Y-129500D01*
X68947Y-130333D01*
X68377Y-130917D01*
X67997Y-131750D01*
X67870Y-132500D01*
X70530D01*
G01X72907Y-131500D02*
X73287Y-132083D01*
X73793Y-132417D01*
X74363Y-132500D01*
X74870Y-132417D01*
X75377Y-132000D01*
X75693Y-131500D01*
X75757Y-131000D01*
X75630Y-130417D01*
X75187Y-130000D01*
X74743Y-129833D01*
X74173D01*
G01X74743D02*
X75123Y-129583D01*
X75440Y-129167D01*
X75567Y-128667D01*
X75440Y-128167D01*
X75123Y-127750D01*
X74553Y-127500D01*
X73983Y-127583D01*
X73413Y-127917D01*
G01X80160Y-132500D02*
Y-127500D01*
X77817Y-131083D01*
X80983D01*
G01X83107Y-131750D02*
X83487Y-132167D01*
X83930Y-132417D01*
X84500Y-132500D01*
X85070Y-132333D01*
X85513Y-132000D01*
X85830Y-131417D01*
X85893Y-130750D01*
X85767Y-130083D01*
X85450Y-129667D01*
X85007Y-129333D01*
X84563Y-129250D01*
X84120Y-129333D01*
X83550Y-129667D01*
X83740Y-127500D01*
X85450D01*
G01X93497Y-132500D02*
Y-127500D01*
X95903D01*
G01X95017Y-129917D02*
X93497D01*
G01X98217Y-132500D02*
X99800Y-127500D01*
X101383Y-132500D01*
G01X100813Y-130750D02*
X98787D01*
G01X103570Y-132500D02*
X106230Y-127500D01*
G01X103570D02*
X106230Y-132500D01*
G01X110000Y-132667D02*
X109873Y-132583D01*
Y-132417D01*
X110000Y-132333D01*
X110127Y-132417D01*
Y-132583D01*
X110000Y-132667D01*
G01Y-130417D02*
X109873Y-130333D01*
Y-130167D01*
X110000Y-130083D01*
X110127Y-130167D01*
Y-130333D01*
X110000Y-130417D01*
G01X114783Y-134167D02*
X114150Y-133333D01*
X113833Y-132500D01*
Y-129167D01*
X114150Y-128333D01*
X114783Y-127500D01*
G01X120200D02*
X119693Y-127667D01*
X119313Y-128083D01*
X119060Y-128583D01*
X118870Y-129250D01*
X118807Y-130000D01*
X118870Y-130750D01*
X119060Y-131417D01*
X119313Y-131917D01*
X119693Y-132333D01*
X120200Y-132500D01*
X120707Y-132333D01*
X121087Y-131917D01*
X121340Y-131417D01*
X121530Y-130750D01*
X121593Y-130000D01*
X121530Y-129250D01*
X121340Y-128583D01*
X121087Y-128083D01*
X120707Y-127667D01*
X120200Y-127500D01*
G01X123907Y-131500D02*
X124287Y-132083D01*
X124793Y-132417D01*
X125363Y-132500D01*
X125870Y-132417D01*
X126377Y-132000D01*
X126693Y-131500D01*
X126757Y-131000D01*
X126630Y-130417D01*
X126187Y-130000D01*
X125743Y-129833D01*
X125173D01*
G01X125743D02*
X126123Y-129583D01*
X126440Y-129167D01*
X126567Y-128667D01*
X126440Y-128167D01*
X126123Y-127750D01*
X125553Y-127500D01*
X124983Y-127583D01*
X124413Y-127917D01*
G01X130717Y-134167D02*
X131350Y-133333D01*
X131667Y-132500D01*
Y-129167D01*
X131350Y-128333D01*
X130717Y-127500D01*
G01X134107Y-131500D02*
X134487Y-132083D01*
X134993Y-132417D01*
X135563Y-132500D01*
X136070Y-132417D01*
X136577Y-132000D01*
X136893Y-131500D01*
X136957Y-131000D01*
X136830Y-130417D01*
X136387Y-130000D01*
X135943Y-129833D01*
X135373D01*
G01X135943D02*
X136323Y-129583D01*
X136640Y-129167D01*
X136767Y-128667D01*
X136640Y-128167D01*
X136323Y-127750D01*
X135753Y-127500D01*
X135183Y-127583D01*
X134613Y-127917D01*
G01X139523Y-131917D02*
X139967Y-132333D01*
X140473Y-132500D01*
X140980Y-132333D01*
X141423Y-131833D01*
X141740Y-131083D01*
X141867Y-130333D01*
Y-129417D01*
X141740Y-128667D01*
X141423Y-128000D01*
X141043Y-127667D01*
X140600Y-127500D01*
X140093Y-127667D01*
X139713Y-128000D01*
X139460Y-128500D01*
X139333Y-129167D01*
X139460Y-129750D01*
X139777Y-130333D01*
X140157Y-130667D01*
X140600Y-130750D01*
X141107Y-130583D01*
X141487Y-130167D01*
X141867Y-129417D01*
G01X145573Y-132500D02*
X145700Y-131417D01*
X145890Y-130500D01*
X146143Y-129667D01*
X146460Y-128750D01*
X146967Y-127500D01*
X144433D01*
G01X149977Y-130833D02*
X151623D01*
G01X154507Y-131500D02*
X154887Y-132083D01*
X155393Y-132417D01*
X155963Y-132500D01*
X156470Y-132417D01*
X156977Y-132000D01*
X157293Y-131500D01*
X157357Y-131000D01*
X157230Y-130417D01*
X156787Y-130000D01*
X156343Y-129833D01*
X155773D01*
G01X156343D02*
X156723Y-129583D01*
X157040Y-129167D01*
X157167Y-128667D01*
X157040Y-128167D01*
X156723Y-127750D01*
X156153Y-127500D01*
X155583Y-127583D01*
X155013Y-127917D01*
G01X159797Y-130417D02*
X160240Y-129833D01*
X160620Y-129500D01*
X161127Y-129333D01*
X161570Y-129500D01*
X161887Y-129833D01*
X162140Y-130333D01*
X162203Y-130917D01*
X162140Y-131417D01*
X161887Y-131917D01*
X161507Y-132333D01*
X161063Y-132500D01*
X160557Y-132333D01*
X160113Y-131833D01*
X159860Y-131083D01*
X159797Y-130250D01*
X159923Y-129167D01*
X160113Y-128583D01*
X160430Y-128000D01*
X160873Y-127583D01*
X161317Y-127500D01*
X161760Y-127667D01*
X162077Y-128083D01*
G01X166100Y-132500D02*
Y-127500D01*
X165340Y-128500D01*
G01Y-132500D02*
X166860D01*
G01X171960D02*
Y-127500D01*
X169617Y-131083D01*
X172783D01*
G01X191000Y-62500D02*
Y-137500D01*
G01Y-112500D02*
X294000D01*
Y-87500D01*
G01X191000D02*
X294000D01*
G01X301507Y-122500D02*
Y-117500D01*
X302773D01*
X303280Y-117750D01*
X303660Y-118083D01*
X303977Y-118583D01*
X304230Y-119167D01*
X304293Y-120000D01*
X304230Y-120833D01*
X303977Y-121417D01*
X303660Y-121917D01*
X303280Y-122250D01*
X302773Y-122500D01*
X301507D01*
G01X306417D02*
X308000Y-117500D01*
X309583Y-122500D01*
G01X309013Y-120750D02*
X306987D01*
G01X313100Y-117500D02*
Y-122500D01*
G01X311643Y-117500D02*
X314557D01*
G01X319467Y-122500D02*
X316933D01*
Y-117500D01*
X319467D01*
G01X318453Y-119917D02*
X316933D01*
G01X323300Y-122667D02*
X323173Y-122583D01*
Y-122417D01*
X323300Y-122333D01*
X323427Y-122417D01*
Y-122583D01*
X323300Y-122667D01*
G01Y-120417D02*
X323173Y-120333D01*
Y-120167D01*
X323300Y-120083D01*
X323427Y-120167D01*
Y-120333D01*
X323300Y-120417D01*
G01X296000Y-62500D02*
Y-137500D01*
G01X294000Y-62500D02*
Y-137500D01*
G01X301633Y-97500D02*
Y-92500D01*
X303153D01*
X303660Y-92750D01*
X304040Y-93333D01*
X304167Y-94000D01*
X304040Y-94667D01*
X303723Y-95167D01*
X303153Y-95417D01*
X301633D01*
G01X306860Y-97667D02*
X309140Y-92500D01*
G01X311643Y-97500D02*
Y-92500D01*
X314557Y-97500D01*
Y-92500D01*
G01X318200Y-97667D02*
X318073Y-97583D01*
Y-97417D01*
X318200Y-97333D01*
X318327Y-97417D01*
Y-97583D01*
X318200Y-97667D01*
G01Y-95417D02*
X318073Y-95333D01*
Y-95167D01*
X318200Y-95083D01*
X318327Y-95167D01*
Y-95333D01*
X318200Y-95417D01*
G01X296000Y-112500D02*
X496000D01*
G01X301633Y-72500D02*
Y-67500D01*
X303153D01*
X303660Y-67750D01*
X304040Y-68333D01*
X304167Y-69000D01*
X304040Y-69667D01*
X303723Y-70167D01*
X303153Y-70417D01*
X301633D01*
G01X306733Y-72500D02*
Y-67500D01*
X308317D01*
X308823Y-67750D01*
X309140Y-68083D01*
X309267Y-68750D01*
X309140Y-69417D01*
X308760Y-69833D01*
X308317Y-70083D01*
X306733D01*
G01X308317D02*
X309267Y-72500D01*
G01X313100D02*
X312593Y-72417D01*
X312150Y-72083D01*
X311770Y-71583D01*
X311517Y-71000D01*
X311390Y-70333D01*
Y-69667D01*
X311517Y-69000D01*
X311770Y-68417D01*
X312150Y-67917D01*
X312593Y-67583D01*
X313100Y-67500D01*
X313607Y-67583D01*
X314050Y-67917D01*
X314430Y-68417D01*
X314683Y-69000D01*
X314810Y-69667D01*
Y-70333D01*
X314683Y-71000D01*
X314430Y-71583D01*
X314050Y-72083D01*
X313607Y-72417D01*
X313100Y-72500D01*
G01X316933Y-71500D02*
X317250Y-72000D01*
X317630Y-72333D01*
X318073Y-72500D01*
X318580Y-72333D01*
X318960Y-72000D01*
X319340Y-71500D01*
X319467Y-70833D01*
Y-67500D01*
G01X324567Y-72500D02*
X322033D01*
Y-67500D01*
X324567D01*
G01X323553Y-69917D02*
X322033D01*
G01X329793Y-67917D02*
X329413Y-67667D01*
X328970Y-67500D01*
X328463D01*
X327893Y-67750D01*
X327450Y-68167D01*
X327133Y-68667D01*
X326880Y-69500D01*
X326817Y-70250D01*
X326943Y-71000D01*
X327133Y-71500D01*
X327513Y-72000D01*
X327957Y-72333D01*
X328400Y-72500D01*
X328843D01*
X329287Y-72333D01*
X329667Y-72083D01*
X329983Y-71750D01*
G01X333500Y-67500D02*
Y-72500D01*
G01X332043Y-67500D02*
X334957D01*
G01X338600Y-72667D02*
X338473Y-72583D01*
Y-72417D01*
X338600Y-72333D01*
X338727Y-72417D01*
Y-72583D01*
X338600Y-72667D01*
G01Y-70417D02*
X338473Y-70333D01*
Y-70167D01*
X338600Y-70083D01*
X338727Y-70167D01*
Y-70333D01*
X338600Y-70417D01*
G01X296000Y-87500D02*
X496000D01*
G01X411000Y-112500D02*
Y-137500D01*
G01X416633Y-122500D02*
Y-117500D01*
X418217D01*
X418723Y-117750D01*
X419040Y-118083D01*
X419167Y-118750D01*
X419040Y-119417D01*
X418660Y-119833D01*
X418217Y-120083D01*
X416633D01*
G01X418217D02*
X419167Y-122500D01*
G01X424267D02*
X421733D01*
Y-117500D01*
X424267D01*
G01X423253Y-119917D02*
X421733D01*
G01X426517Y-117500D02*
X428100Y-122500D01*
X429683Y-117500D01*
G01X433200Y-122667D02*
X433073Y-122583D01*
Y-122417D01*
X433200Y-122333D01*
X433327Y-122417D01*
Y-122583D01*
X433200Y-122667D01*
G01Y-120417D02*
X433073Y-120333D01*
Y-120167D01*
X433200Y-120083D01*
X433327Y-120167D01*
Y-120333D01*
X433200Y-120417D01*
G01X460000Y-112500D02*
Y-137500D01*
G01X-723776Y2987387D02*
Y-376795D01*
Y-489221D01*
X1782976D01*
Y-376795D01*
Y2987387D01*
X-723776D01*
G01X6705Y-124160D02*
X7332Y-124685D01*
X8037Y-125000D01*
X8663D01*
X9290Y-124685D01*
X9760Y-124160D01*
X9995Y-123425D01*
X9838Y-122690D01*
X9447Y-122060D01*
X8742Y-121640D01*
X7802Y-121430D01*
X7253Y-121010D01*
X7018Y-120275D01*
X7175Y-119540D01*
X7567Y-119015D01*
X8115Y-118700D01*
X8663D01*
X9212Y-118910D01*
X9682Y-119435D01*
G01X13005Y-125000D02*
Y-118700D01*
G01X16295D02*
Y-125000D01*
G01Y-121850D02*
X13005D01*
G01X20010Y-118700D02*
X21890D01*
G01X20950D02*
Y-125000D01*
G01X20010D02*
X21890D01*
G01X28817D02*
X25683D01*
Y-118700D01*
X28817D01*
G01X27563Y-121745D02*
X25683D01*
G01X31748Y-125000D02*
Y-118700D01*
X35352Y-125000D01*
Y-118700D01*
G01X39693Y-126155D02*
X40007Y-124790D01*
G01X46150Y-118700D02*
Y-125000D01*
G01X44348Y-118700D02*
X47952D01*
G01X50492Y-125000D02*
X52450Y-118700D01*
X54408Y-125000D01*
G01X53703Y-122795D02*
X51197D01*
G01X57810Y-118700D02*
X59690D01*
G01X58750D02*
Y-125000D01*
G01X57810D02*
X59690D01*
G01X62700Y-118700D02*
X63797Y-125000D01*
X65050Y-118700D01*
X66303Y-125000D01*
X67400Y-118700D01*
G01X69392Y-125000D02*
X71350Y-118700D01*
X73308Y-125000D01*
G01X72603Y-122795D02*
X70097D01*
G01X75848Y-125000D02*
Y-118700D01*
X79452Y-125000D01*
Y-118700D01*
G01X88683Y-125000D02*
Y-118700D01*
X90642D01*
X91268Y-119015D01*
X91660Y-119435D01*
X91817Y-120275D01*
X91660Y-121115D01*
X91190Y-121640D01*
X90642Y-121955D01*
X88683D01*
G01X90642D02*
X91817Y-125000D01*
G01X96550Y-125210D02*
X96393Y-125105D01*
Y-124895D01*
X96550Y-124790D01*
X96707Y-124895D01*
Y-125105D01*
X96550Y-125210D01*
G01X102850Y-125000D02*
X102223Y-124895D01*
X101675Y-124475D01*
X101205Y-123845D01*
X100892Y-123110D01*
X100735Y-122270D01*
Y-121430D01*
X100892Y-120590D01*
X101205Y-119855D01*
X101675Y-119225D01*
X102223Y-118805D01*
X102850Y-118700D01*
X103477Y-118805D01*
X104025Y-119225D01*
X104495Y-119855D01*
X104808Y-120590D01*
X104965Y-121430D01*
Y-122270D01*
X104808Y-123110D01*
X104495Y-123845D01*
X104025Y-124475D01*
X103477Y-124895D01*
X102850Y-125000D01*
G01X109150Y-125210D02*
X108993Y-125105D01*
Y-124895D01*
X109150Y-124790D01*
X109307Y-124895D01*
Y-125105D01*
X109150Y-125210D01*
G01X117173Y-119225D02*
X116703Y-118910D01*
X116155Y-118700D01*
X115528D01*
X114823Y-119015D01*
X114275Y-119540D01*
X113883Y-120170D01*
X113570Y-121220D01*
X113492Y-122165D01*
X113648Y-123110D01*
X113883Y-123740D01*
X114353Y-124370D01*
X114902Y-124790D01*
X115450Y-125000D01*
X115998D01*
X116547Y-124790D01*
X117017Y-124475D01*
X117408Y-124055D01*
G01X121750Y-125210D02*
X121593Y-125105D01*
Y-124895D01*
X121750Y-124790D01*
X121907Y-124895D01*
Y-125105D01*
X121750Y-125210D01*
G01X6627Y-115000D02*
Y-108700D01*
G01X9603D02*
X6627Y-112585D01*
G01X10073Y-115000D02*
X7958Y-110800D01*
G01X12927Y-108700D02*
Y-113215D01*
X13240Y-114160D01*
X13867Y-114790D01*
X14650Y-115000D01*
X15433Y-114790D01*
X16060Y-114160D01*
X16373Y-113215D01*
Y-108700D01*
G01X22517Y-115000D02*
X19383D01*
Y-108700D01*
X22517D01*
G01X21263Y-111745D02*
X19383D01*
G01X26310Y-108700D02*
X28190D01*
G01X27250D02*
Y-115000D01*
G01X26310D02*
X28190D01*
G01X38205Y-114160D02*
X38832Y-114685D01*
X39537Y-115000D01*
X40163D01*
X40790Y-114685D01*
X41260Y-114160D01*
X41495Y-113425D01*
X41338Y-112690D01*
X40947Y-112060D01*
X40242Y-111640D01*
X39302Y-111430D01*
X38753Y-111010D01*
X38518Y-110275D01*
X38675Y-109540D01*
X39067Y-109015D01*
X39615Y-108700D01*
X40163D01*
X40712Y-108910D01*
X41182Y-109435D01*
G01X44505Y-115000D02*
Y-108700D01*
G01X47795D02*
Y-115000D01*
G01Y-111850D02*
X44505D01*
G01X50492Y-115000D02*
X52450Y-108700D01*
X54408Y-115000D01*
G01X53703Y-112795D02*
X51197D01*
G01X56948Y-115000D02*
Y-108700D01*
X60552Y-115000D01*
Y-108700D01*
G01X69705Y-115000D02*
Y-108700D01*
G01X72995D02*
Y-115000D01*
G01Y-111850D02*
X69705D01*
G01X76005Y-114160D02*
X76632Y-114685D01*
X77337Y-115000D01*
X77963D01*
X78590Y-114685D01*
X79060Y-114160D01*
X79295Y-113425D01*
X79138Y-112690D01*
X78747Y-112060D01*
X78042Y-111640D01*
X77102Y-111430D01*
X76553Y-111010D01*
X76318Y-110275D01*
X76475Y-109540D01*
X76867Y-109015D01*
X77415Y-108700D01*
X77963D01*
X78512Y-108910D01*
X78982Y-109435D01*
G01X83010Y-108700D02*
X84890D01*
G01X83950D02*
Y-115000D01*
G01X83010D02*
X84890D01*
G01X88292D02*
X90250Y-108700D01*
X92208Y-115000D01*
G01X91503Y-112795D02*
X88997D01*
G01X94748Y-115000D02*
Y-108700D01*
X98352Y-115000D01*
Y-108700D01*
G01X103320Y-111850D02*
X104887D01*
Y-113740D01*
X104417Y-114370D01*
X103868Y-114790D01*
X103085Y-115000D01*
X102302Y-114790D01*
X101753Y-114370D01*
X101283Y-113740D01*
X100970Y-113005D01*
X100813Y-112165D01*
Y-111430D01*
X100970Y-110800D01*
X101283Y-110065D01*
X101753Y-109435D01*
X102223Y-109015D01*
X102850Y-108700D01*
X103398D01*
X104025Y-108910D01*
X104495Y-109330D01*
G01X108993Y-116155D02*
X109307Y-114790D01*
G01X115450Y-108700D02*
Y-115000D01*
G01X113648Y-108700D02*
X117252D01*
G01X119792Y-115000D02*
X121750Y-108700D01*
X123708Y-115000D01*
G01X123003Y-112795D02*
X120497D01*
G01X128050Y-115000D02*
X127423Y-114895D01*
X126875Y-114475D01*
X126405Y-113845D01*
X126092Y-113110D01*
X125935Y-112270D01*
Y-111430D01*
X126092Y-110590D01*
X126405Y-109855D01*
X126875Y-109225D01*
X127423Y-108805D01*
X128050Y-108700D01*
X128677Y-108805D01*
X129225Y-109225D01*
X129695Y-109855D01*
X130008Y-110590D01*
X130165Y-111430D01*
Y-112270D01*
X130008Y-113110D01*
X129695Y-113845D01*
X129225Y-114475D01*
X128677Y-114895D01*
X128050Y-115000D01*
G01X140650D02*
Y-112165D01*
X139083Y-108700D01*
G01X142217D02*
X140650Y-112165D01*
G01X145227Y-108700D02*
Y-113215D01*
X145540Y-114160D01*
X146167Y-114790D01*
X146950Y-115000D01*
X147733Y-114790D01*
X148360Y-114160D01*
X148673Y-113215D01*
Y-108700D01*
G01X151292Y-115000D02*
X153250Y-108700D01*
X155208Y-115000D01*
G01X154503Y-112795D02*
X151997D01*
G01X157748Y-115000D02*
Y-108700D01*
X161352Y-115000D01*
Y-108700D01*
G01X30650Y-92300D02*
X28130Y-91883D01*
X25925Y-90217D01*
X24035Y-87717D01*
X22775Y-84800D01*
X22145Y-81467D01*
Y-78133D01*
X22775Y-74800D01*
X24035Y-71883D01*
X25925Y-69384D01*
X28130Y-67717D01*
X30650Y-67300D01*
X33170Y-67717D01*
X35375Y-69384D01*
X37265Y-71883D01*
X38525Y-74800D01*
X39155Y-78133D01*
Y-81467D01*
X38525Y-84800D01*
X37265Y-87717D01*
X35375Y-90217D01*
X33170Y-91883D01*
X30650Y-92300D01*
G01X33170Y-85633D02*
X36950Y-92300D01*
G01X50495Y-75634D02*
Y-87300D01*
X51755Y-90217D01*
X53645Y-91883D01*
X55850Y-92300D01*
X58055Y-91883D01*
X59945Y-90217D01*
X61205Y-87300D01*
G01Y-92300D02*
Y-75634D01*
G01X86720Y-92300D02*
Y-75634D01*
G01Y-78550D02*
X85460Y-76884D01*
X83570Y-76050D01*
X81365Y-75634D01*
X79160Y-76467D01*
X77270Y-78133D01*
X76010Y-80634D01*
X75380Y-83967D01*
X76010Y-87300D01*
X77270Y-89801D01*
X79160Y-91467D01*
X81365Y-92300D01*
X83570Y-91883D01*
X85460Y-90634D01*
X86720Y-88967D01*
G01X100895Y-92300D02*
Y-75634D01*
G01Y-79800D02*
X102155Y-77717D01*
X104045Y-76050D01*
X106565Y-75634D01*
X108770Y-76050D01*
X110660Y-77717D01*
X111605Y-80634D01*
Y-92300D01*
G01X131450Y-67300D02*
Y-92300D01*
G01X127040Y-75634D02*
X135860D01*
G01X162320Y-92300D02*
Y-75634D01*
G01Y-78550D02*
X161060Y-76884D01*
X159170Y-76050D01*
X156965Y-75634D01*
X154760Y-76467D01*
X152870Y-78133D01*
X151610Y-80634D01*
X150980Y-83967D01*
X151610Y-87300D01*
X152870Y-89801D01*
X154760Y-91467D01*
X156965Y-92300D01*
X159170Y-91883D01*
X161060Y-90634D01*
X162320Y-88967D01*
G01X6548Y-105000D02*
Y-98700D01*
X10152Y-105000D01*
Y-98700D01*
G01X14650Y-105000D02*
X14023Y-104895D01*
X13475Y-104475D01*
X13005Y-103845D01*
X12692Y-103110D01*
X12535Y-102270D01*
Y-101430D01*
X12692Y-100590D01*
X13005Y-99855D01*
X13475Y-99225D01*
X14023Y-98805D01*
X14650Y-98700D01*
X15277Y-98805D01*
X15825Y-99225D01*
X16295Y-99855D01*
X16608Y-100590D01*
X16765Y-101430D01*
Y-102270D01*
X16608Y-103110D01*
X16295Y-103845D01*
X15825Y-104475D01*
X15277Y-104895D01*
X14650Y-105000D01*
G01X20950Y-105210D02*
X20793Y-105105D01*
Y-104895D01*
X20950Y-104790D01*
X21107Y-104895D01*
Y-105105D01*
X20950Y-105210D01*
G01X27250Y-105000D02*
Y-98700D01*
X26310Y-99960D01*
G01Y-105000D02*
X28190D01*
G01X33550D02*
X34098Y-104895D01*
X34725Y-104580D01*
X35117Y-104055D01*
X35273Y-103320D01*
X35117Y-102585D01*
X34647Y-101955D01*
X33942Y-101640D01*
X33158D01*
X32688Y-101430D01*
X32297Y-100905D01*
X32140Y-100170D01*
X32375Y-99435D01*
X32923Y-98910D01*
X33550Y-98700D01*
X34177Y-98910D01*
X34725Y-99435D01*
X34960Y-100170D01*
X34803Y-100905D01*
X34412Y-101430D01*
X33942Y-101640D01*
X33158D01*
X32453Y-101955D01*
X31983Y-102585D01*
X31827Y-103320D01*
X31983Y-104055D01*
X32375Y-104580D01*
X33002Y-104895D01*
X33550Y-105000D01*
G01X39850D02*
X40398Y-104895D01*
X41025Y-104580D01*
X41417Y-104055D01*
X41573Y-103320D01*
X41417Y-102585D01*
X40947Y-101955D01*
X40242Y-101640D01*
X39458D01*
X38988Y-101430D01*
X38597Y-100905D01*
X38440Y-100170D01*
X38675Y-99435D01*
X39223Y-98910D01*
X39850Y-98700D01*
X40477Y-98910D01*
X41025Y-99435D01*
X41260Y-100170D01*
X41103Y-100905D01*
X40712Y-101430D01*
X40242Y-101640D01*
X39458D01*
X38753Y-101955D01*
X38283Y-102585D01*
X38127Y-103320D01*
X38283Y-104055D01*
X38675Y-104580D01*
X39302Y-104895D01*
X39850Y-105000D01*
G01X45993Y-106155D02*
X46307Y-104790D01*
G01X50100Y-98700D02*
X51197Y-105000D01*
X52450Y-98700D01*
X53703Y-105000D01*
X54800Y-98700D01*
G01X60317Y-105000D02*
X57183D01*
Y-98700D01*
X60317D01*
G01X59063Y-101745D02*
X57183D01*
G01X63248Y-105000D02*
Y-98700D01*
X66852Y-105000D01*
Y-98700D01*
G01X76005Y-105000D02*
Y-98700D01*
G01X79295D02*
Y-105000D01*
G01Y-101850D02*
X76005D01*
G01X81600Y-98700D02*
X82697Y-105000D01*
X83950Y-98700D01*
X85203Y-105000D01*
X86300Y-98700D01*
G01X88292Y-105000D02*
X90250Y-98700D01*
X92208Y-105000D01*
G01X91503Y-102795D02*
X88997D01*
G01X101362Y-99750D02*
X101832Y-99120D01*
X102380Y-98805D01*
X103007Y-98700D01*
X103790Y-98910D01*
X104338Y-99435D01*
X104495Y-100065D01*
X104417Y-100695D01*
X104103Y-101220D01*
X102537Y-102270D01*
X101832Y-103005D01*
X101362Y-104055D01*
X101205Y-105000D01*
X104495D01*
G01X107348D02*
Y-98700D01*
X110952Y-105000D01*
Y-98700D01*
G01X113727Y-105000D02*
Y-98700D01*
X115293D01*
X115920Y-99015D01*
X116390Y-99435D01*
X116782Y-100065D01*
X117095Y-100800D01*
X117173Y-101850D01*
X117095Y-102900D01*
X116782Y-103635D01*
X116390Y-104265D01*
X115920Y-104685D01*
X115293Y-105000D01*
X113727D01*
G01X126483D02*
Y-98700D01*
X128442D01*
X129068Y-99015D01*
X129460Y-99435D01*
X129617Y-100275D01*
X129460Y-101115D01*
X128990Y-101640D01*
X128442Y-101955D01*
X126483D01*
G01X128442D02*
X129617Y-105000D01*
G01X132627D02*
Y-98700D01*
X134193D01*
X134820Y-99015D01*
X135290Y-99435D01*
X135682Y-100065D01*
X135995Y-100800D01*
X136073Y-101850D01*
X135995Y-102900D01*
X135682Y-103635D01*
X135290Y-104265D01*
X134820Y-104685D01*
X134193Y-105000D01*
X132627D01*
G01X140650Y-105210D02*
X140493Y-105105D01*
Y-104895D01*
X140650Y-104790D01*
X140807Y-104895D01*
Y-105105D01*
X140650Y-105210D01*
G01X213500Y-105000D02*
Y-97000D01*
X215900D01*
X216700Y-97400D01*
X217300Y-98333D01*
X217500Y-99400D01*
X217300Y-100467D01*
X216800Y-101267D01*
X215900Y-101667D01*
X213500D01*
G01X221000Y-105000D02*
X223500Y-97000D01*
X226000Y-105000D01*
G01X225100Y-102200D02*
X221900D01*
G01X229400Y-103934D02*
X230200Y-104600D01*
X231100Y-105000D01*
X231900D01*
X232700Y-104600D01*
X233300Y-103934D01*
X233600Y-103000D01*
X233400Y-102067D01*
X232900Y-101267D01*
X232000Y-100733D01*
X230800Y-100467D01*
X230100Y-99933D01*
X229800Y-99000D01*
X230000Y-98067D01*
X230500Y-97400D01*
X231200Y-97000D01*
X231900D01*
X232600Y-97267D01*
X233200Y-97933D01*
G01X239500Y-97000D02*
Y-105000D01*
G01X237200Y-97000D02*
X241800D01*
G01X246200Y-102333D02*
X248800D01*
G01X256300Y-100733D02*
X256700Y-100333D01*
X257000Y-99667D01*
X257200Y-98733D01*
X257000Y-97933D01*
X256600Y-97400D01*
X255900Y-97000D01*
X253200D01*
Y-105000D01*
X256500D01*
X257200Y-104467D01*
X257600Y-103667D01*
X257800Y-102733D01*
X257600Y-101800D01*
X257000Y-101000D01*
X256300Y-100733D01*
X253200D01*
G01X263500Y-105000D02*
X262700Y-104867D01*
X262000Y-104333D01*
X261400Y-103533D01*
X261000Y-102600D01*
X260800Y-101533D01*
Y-100467D01*
X261000Y-99400D01*
X261400Y-98467D01*
X262000Y-97667D01*
X262700Y-97133D01*
X263500Y-97000D01*
X264300Y-97133D01*
X265000Y-97667D01*
X265600Y-98467D01*
X266000Y-99400D01*
X266200Y-100467D01*
Y-101533D01*
X266000Y-102600D01*
X265600Y-103533D01*
X265000Y-104333D01*
X264300Y-104867D01*
X263500Y-105000D01*
G01X271500Y-97000D02*
Y-105000D01*
G01X269200Y-97000D02*
X273800D01*
G01X202000Y-72000D02*
Y-80000D01*
X206000D01*
G01X213800D02*
Y-74667D01*
G01Y-75600D02*
X213400Y-75067D01*
X212800Y-74800D01*
X212100Y-74667D01*
X211400Y-74933D01*
X210800Y-75467D01*
X210400Y-76267D01*
X210200Y-77333D01*
X210400Y-78400D01*
X210800Y-79200D01*
X211400Y-79733D01*
X212100Y-80000D01*
X212800Y-79867D01*
X213400Y-79467D01*
X213800Y-78934D01*
G01X217900Y-82400D02*
X218500Y-82667D01*
X219300Y-82400D01*
X219800Y-81867D01*
X220200Y-81200D01*
X220800Y-79067D01*
X222100Y-74667D01*
G01X218900D02*
X220800Y-79067D01*
G01X226500Y-76400D02*
X229700D01*
X229400Y-75467D01*
X228900Y-74933D01*
X228200Y-74667D01*
X227500Y-74800D01*
X226900Y-75200D01*
X226500Y-76133D01*
X226300Y-76934D01*
Y-77733D01*
X226500Y-78533D01*
X227000Y-79333D01*
X227600Y-79867D01*
X228300Y-80000D01*
X229000Y-79733D01*
X229700Y-78934D01*
G01X234600Y-80000D02*
Y-74667D01*
G01Y-75733D02*
X235100Y-75200D01*
X235600Y-74800D01*
X236300Y-74667D01*
X236800Y-74800D01*
X237400Y-75200D01*
G01X223400Y-128934D02*
X224200Y-129600D01*
X225100Y-130000D01*
X225900D01*
X226700Y-129600D01*
X227300Y-128934D01*
X227600Y-128000D01*
X227400Y-127067D01*
X226900Y-126267D01*
X226000Y-125733D01*
X224800Y-125467D01*
X224100Y-124933D01*
X223800Y-124000D01*
X224000Y-123067D01*
X224500Y-122400D01*
X225200Y-122000D01*
X225900D01*
X226600Y-122267D01*
X227200Y-122933D01*
G01X235300Y-130000D02*
Y-124667D01*
G01Y-125600D02*
X234900Y-125067D01*
X234300Y-124800D01*
X233600Y-124667D01*
X232900Y-124933D01*
X232300Y-125467D01*
X231900Y-126267D01*
X231700Y-127333D01*
X231900Y-128400D01*
X232300Y-129200D01*
X232900Y-129733D01*
X233600Y-130000D01*
X234300Y-129867D01*
X234900Y-129467D01*
X235300Y-128934D01*
G01X239800Y-130000D02*
Y-124667D01*
G01Y-126000D02*
X240200Y-125333D01*
X240800Y-124800D01*
X241600Y-124667D01*
X242300Y-124800D01*
X242900Y-125333D01*
X243200Y-126267D01*
Y-130000D01*
G01X251300Y-122000D02*
Y-130000D01*
G01Y-128800D02*
X250900Y-129467D01*
X250300Y-129867D01*
X249600Y-130000D01*
X248800Y-129733D01*
X248200Y-129067D01*
X247800Y-128267D01*
X247700Y-127333D01*
X247800Y-126400D01*
X248200Y-125600D01*
X248800Y-124933D01*
X249600Y-124667D01*
X250300Y-124800D01*
X250800Y-125067D01*
X251300Y-125600D01*
G01X255400Y-132400D02*
X256000Y-132667D01*
X256800Y-132400D01*
X257300Y-131867D01*
X257700Y-131200D01*
X258300Y-129067D01*
X259600Y-124667D01*
G01X256400D02*
X258300Y-129067D01*
G01X328600Y-123333D02*
X329200Y-122533D01*
X329900Y-122133D01*
X330700Y-122000D01*
X331700Y-122267D01*
X332400Y-122933D01*
X332600Y-123733D01*
X332500Y-124534D01*
X332100Y-125200D01*
X330100Y-126533D01*
X329200Y-127467D01*
X328600Y-128800D01*
X328400Y-130000D01*
X332600D01*
G01X338500Y-122000D02*
X337700Y-122267D01*
X337100Y-122933D01*
X336700Y-123733D01*
X336400Y-124800D01*
X336300Y-126000D01*
X336400Y-127200D01*
X336700Y-128267D01*
X337100Y-129067D01*
X337700Y-129733D01*
X338500Y-130000D01*
X339300Y-129733D01*
X339900Y-129067D01*
X340300Y-128267D01*
X340600Y-127200D01*
X340700Y-126000D01*
X340600Y-124800D01*
X340300Y-123733D01*
X339900Y-122933D01*
X339300Y-122267D01*
X338500Y-122000D01*
G01X346500Y-130000D02*
Y-122000D01*
X345300Y-123600D01*
G01Y-130000D02*
X347700D01*
G01X352600Y-123333D02*
X353200Y-122533D01*
X353900Y-122133D01*
X354700Y-122000D01*
X355700Y-122267D01*
X356400Y-122933D01*
X356600Y-123733D01*
X356500Y-124534D01*
X356100Y-125200D01*
X354100Y-126533D01*
X353200Y-127467D01*
X352600Y-128800D01*
X352400Y-130000D01*
X356600D01*
G01X360700Y-130267D02*
X364300Y-122000D01*
G01X370500D02*
X369700Y-122267D01*
X369100Y-122933D01*
X368700Y-123733D01*
X368400Y-124800D01*
X368300Y-126000D01*
X368400Y-127200D01*
X368700Y-128267D01*
X369100Y-129067D01*
X369700Y-129733D01*
X370500Y-130000D01*
X371300Y-129733D01*
X371900Y-129067D01*
X372300Y-128267D01*
X372600Y-127200D01*
X372700Y-126000D01*
X372600Y-124800D01*
X372300Y-123733D01*
X371900Y-122933D01*
X371300Y-122267D01*
X370500Y-122000D01*
G01X376800Y-129067D02*
X377500Y-129733D01*
X378300Y-130000D01*
X379100Y-129733D01*
X379800Y-128934D01*
X380300Y-127733D01*
X380500Y-126533D01*
Y-125067D01*
X380300Y-123867D01*
X379800Y-122800D01*
X379200Y-122267D01*
X378500Y-122000D01*
X377700Y-122267D01*
X377100Y-122800D01*
X376700Y-123600D01*
X376500Y-124667D01*
X376700Y-125600D01*
X377200Y-126533D01*
X377800Y-127067D01*
X378500Y-127200D01*
X379300Y-126934D01*
X379900Y-126267D01*
X380500Y-125067D01*
G01X384700Y-130267D02*
X388300Y-122000D01*
G01X392600Y-123333D02*
X393200Y-122533D01*
X393900Y-122133D01*
X394700Y-122000D01*
X395700Y-122267D01*
X396400Y-122933D01*
X396600Y-123733D01*
X396500Y-124534D01*
X396100Y-125200D01*
X394100Y-126533D01*
X393200Y-127467D01*
X392600Y-128800D01*
X392400Y-130000D01*
X396600D01*
G01X402500D02*
X403200Y-129867D01*
X404000Y-129467D01*
X404500Y-128800D01*
X404700Y-127867D01*
X404500Y-126934D01*
X403900Y-126133D01*
X403000Y-125733D01*
X402000D01*
X401400Y-125467D01*
X400900Y-124800D01*
X400700Y-123867D01*
X401000Y-122933D01*
X401700Y-122267D01*
X402500Y-122000D01*
X403300Y-122267D01*
X404000Y-122933D01*
X404300Y-123867D01*
X404100Y-124800D01*
X403600Y-125467D01*
X403000Y-125733D01*
X402000D01*
X401100Y-126133D01*
X400500Y-126934D01*
X400300Y-127867D01*
X400500Y-128800D01*
X401000Y-129467D01*
X401800Y-129867D01*
X402500Y-130000D01*
G01X328300Y-105000D02*
Y-97000D01*
X330300D01*
X331100Y-97400D01*
X331700Y-97933D01*
X332200Y-98733D01*
X332600Y-99667D01*
X332700Y-101000D01*
X332600Y-102333D01*
X332200Y-103267D01*
X331700Y-104067D01*
X331100Y-104600D01*
X330300Y-105000D01*
X328300D01*
G01X336000D02*
X338500Y-97000D01*
X341000Y-105000D01*
G01X340100Y-102200D02*
X336900D01*
G01X346500Y-97000D02*
X345700Y-97267D01*
X345100Y-97933D01*
X344700Y-98733D01*
X344400Y-99800D01*
X344300Y-101000D01*
X344400Y-102200D01*
X344700Y-103267D01*
X345100Y-104067D01*
X345700Y-104733D01*
X346500Y-105000D01*
X347300Y-104733D01*
X347900Y-104067D01*
X348300Y-103267D01*
X348600Y-102200D01*
X348700Y-101000D01*
X348600Y-99800D01*
X348300Y-98733D01*
X347900Y-97933D01*
X347300Y-97267D01*
X346500Y-97000D01*
G01X354500D02*
Y-105000D01*
G01X352200Y-97000D02*
X356800D01*
G01X360600Y-101667D02*
X361300Y-100733D01*
X361900Y-100200D01*
X362700Y-99933D01*
X363400Y-100200D01*
X363900Y-100733D01*
X364300Y-101533D01*
X364400Y-102467D01*
X364300Y-103267D01*
X363900Y-104067D01*
X363300Y-104733D01*
X362600Y-105000D01*
X361800Y-104733D01*
X361100Y-103934D01*
X360700Y-102733D01*
X360600Y-101400D01*
X360800Y-99667D01*
X361100Y-98733D01*
X361600Y-97800D01*
X362300Y-97133D01*
X363000Y-97000D01*
X363700Y-97267D01*
X364200Y-97933D01*
G01X367900Y-105000D02*
Y-97000D01*
X370500Y-103667D01*
X373100Y-97000D01*
Y-105000D01*
G01X378500Y-97000D02*
Y-105000D01*
G01X376200Y-97000D02*
X380800D01*
G01X387300Y-100733D02*
X387700Y-100333D01*
X388000Y-99667D01*
X388200Y-98733D01*
X388000Y-97933D01*
X387600Y-97400D01*
X386900Y-97000D01*
X384200D01*
Y-105000D01*
X387500D01*
X388200Y-104467D01*
X388600Y-103667D01*
X388800Y-102733D01*
X388600Y-101800D01*
X388000Y-101000D01*
X387300Y-100733D01*
X384200D01*
G01X394500Y-105000D02*
X395200Y-104867D01*
X396000Y-104467D01*
X396500Y-103800D01*
X396700Y-102867D01*
X396500Y-101934D01*
X395900Y-101133D01*
X395000Y-100733D01*
X394000D01*
X393400Y-100467D01*
X392900Y-99800D01*
X392700Y-98867D01*
X393000Y-97933D01*
X393700Y-97267D01*
X394500Y-97000D01*
X395300Y-97267D01*
X396000Y-97933D01*
X396300Y-98867D01*
X396100Y-99800D01*
X395600Y-100467D01*
X395000Y-100733D01*
X394000D01*
X393100Y-101133D01*
X392500Y-101934D01*
X392300Y-102867D01*
X392500Y-103800D01*
X393000Y-104467D01*
X393800Y-104867D01*
X394500Y-105000D01*
G01X400300D02*
Y-97000D01*
X402300D01*
X403100Y-97400D01*
X403700Y-97933D01*
X404200Y-98733D01*
X404600Y-99667D01*
X404700Y-101000D01*
X404600Y-102333D01*
X404200Y-103267D01*
X403700Y-104067D01*
X403100Y-104600D01*
X402300Y-105000D01*
X400300D01*
G01X410500Y-97000D02*
X409700Y-97267D01*
X409100Y-97933D01*
X408700Y-98733D01*
X408400Y-99800D01*
X408300Y-101000D01*
X408400Y-102200D01*
X408700Y-103267D01*
X409100Y-104067D01*
X409700Y-104733D01*
X410500Y-105000D01*
X411300Y-104733D01*
X411900Y-104067D01*
X412300Y-103267D01*
X412600Y-102200D01*
X412700Y-101000D01*
X412600Y-99800D01*
X412300Y-98733D01*
X411900Y-97933D01*
X411300Y-97267D01*
X410500Y-97000D01*
G01X350500Y-72000D02*
Y-80000D01*
G01X348200Y-72000D02*
X352800D01*
G01X356600Y-76667D02*
X357300Y-75733D01*
X357900Y-75200D01*
X358700Y-74933D01*
X359400Y-75200D01*
X359900Y-75733D01*
X360300Y-76533D01*
X360400Y-77467D01*
X360300Y-78267D01*
X359900Y-79067D01*
X359300Y-79733D01*
X358600Y-80000D01*
X357800Y-79733D01*
X357100Y-78934D01*
X356700Y-77733D01*
X356600Y-76400D01*
X356800Y-74667D01*
X357100Y-73733D01*
X357600Y-72800D01*
X358300Y-72133D01*
X359000Y-72000D01*
X359700Y-72267D01*
X360200Y-72933D01*
G01X363900Y-80000D02*
Y-72000D01*
X366500Y-78667D01*
X369100Y-72000D01*
Y-80000D01*
G01X371500Y-82667D02*
X377500D01*
G01X380500Y-80000D02*
Y-72000D01*
X382900D01*
X383700Y-72400D01*
X384300Y-73333D01*
X384500Y-74400D01*
X384300Y-75467D01*
X383800Y-76267D01*
X382900Y-76667D01*
X380500D01*
G01X388300Y-80000D02*
Y-72000D01*
X390300D01*
X391100Y-72400D01*
X391700Y-72933D01*
X392200Y-73733D01*
X392600Y-74667D01*
X392700Y-76000D01*
X392600Y-77333D01*
X392200Y-78267D01*
X391700Y-79067D01*
X391100Y-79600D01*
X390300Y-80000D01*
X388300D01*
G01X399300Y-75733D02*
X399700Y-75333D01*
X400000Y-74667D01*
X400200Y-73733D01*
X400000Y-72933D01*
X399600Y-72400D01*
X398900Y-72000D01*
X396200D01*
Y-80000D01*
X399500D01*
X400200Y-79467D01*
X400600Y-78667D01*
X400800Y-77733D01*
X400600Y-76800D01*
X400000Y-76000D01*
X399300Y-75733D01*
X396200D01*
G01X403500Y-82667D02*
X409500D01*
G01X412300Y-80000D02*
Y-72000D01*
X414300D01*
X415100Y-72400D01*
X415700Y-72933D01*
X416200Y-73733D01*
X416600Y-74667D01*
X416700Y-76000D01*
X416600Y-77333D01*
X416200Y-78267D01*
X415700Y-79067D01*
X415100Y-79600D01*
X414300Y-80000D01*
X412300D01*
G01X419500Y-82667D02*
X425500D01*
G01X431300Y-75733D02*
X431700Y-75333D01*
X432000Y-74667D01*
X432200Y-73733D01*
X432000Y-72933D01*
X431600Y-72400D01*
X430900Y-72000D01*
X428200D01*
Y-80000D01*
X431500D01*
X432200Y-79467D01*
X432600Y-78667D01*
X432800Y-77733D01*
X432600Y-76800D01*
X432000Y-76000D01*
X431300Y-75733D01*
X428200D01*
G01X436300Y-80000D02*
Y-72000D01*
X438300D01*
X439100Y-72400D01*
X439700Y-72933D01*
X440200Y-73733D01*
X440600Y-74667D01*
X440700Y-76000D01*
X440600Y-77333D01*
X440200Y-78267D01*
X439700Y-79067D01*
X439100Y-79600D01*
X438300Y-80000D01*
X436300D01*
G01X443300Y-130000D02*
Y-122000D01*
X445300D01*
X446100Y-122400D01*
X446700Y-122933D01*
X447200Y-123733D01*
X447600Y-124667D01*
X447700Y-126000D01*
X447600Y-127333D01*
X447200Y-128267D01*
X446700Y-129067D01*
X446100Y-129600D01*
X445300Y-130000D01*
X443300D01*
G01X473000D02*
Y-122000D01*
X471800Y-123600D01*
G01Y-130000D02*
X474200D01*
G01X478800Y-128800D02*
X479400Y-129467D01*
X480100Y-129867D01*
X481000Y-130000D01*
X481900Y-129733D01*
X482600Y-129200D01*
X483100Y-128267D01*
X483200Y-127200D01*
X483000Y-126133D01*
X482500Y-125467D01*
X481800Y-124933D01*
X481100Y-124800D01*
X480400Y-124933D01*
X479500Y-125467D01*
X479800Y-122000D01*
X482500D01*
G54D15*
X9606Y599901D03*
Y627264D03*
Y1471949D03*
Y1499311D03*
G54D16*
X18995Y1612992D03*
X53995Y518701D03*
G54D17*
X23402Y1668874D03*
Y1685410D03*
Y1701945D03*
Y1718480D03*
Y1735016D03*
Y1751551D03*
Y1768087D03*
Y1784622D03*
Y1817693D03*
Y1801158D03*
X45056Y1668874D03*
Y1685410D03*
Y1701945D03*
Y1718480D03*
Y1735016D03*
Y1751551D03*
Y1768087D03*
Y1784622D03*
Y1801158D03*
G54D18*
X49441Y1238962D03*
X46980Y1335843D03*
Y1325843D03*
Y1315843D03*
Y1320843D03*
Y1330843D03*
Y1345843D03*
Y1340843D03*
X61888Y666012D03*
X57124Y675327D03*
X54483Y679810D03*
X59236Y670758D03*
X70865Y854278D03*
Y872278D03*
Y866278D03*
Y860278D03*
Y897750D03*
Y890116D03*
X61866Y1309190D03*
X67568Y1307829D03*
X54543Y1308995D03*
X61866Y1342104D03*
X95775Y751469D03*
X92216Y899865D03*
X90708Y878615D03*
X92633Y907404D03*
X92989Y927334D03*
X98139Y990959D03*
X82763Y1060051D03*
X96684Y1081791D03*
X96510Y1395382D03*
X106958Y26285D03*
X107405Y49898D03*
X107037Y34687D03*
X106836Y376461D03*
X106709Y391219D03*
X107025Y725368D03*
X106935Y745139D03*
X107173Y735219D03*
X100687Y999391D03*
X107351Y1093484D03*
X107235Y1081791D03*
X107215Y1072208D03*
X105152Y1118381D03*
X100719Y1312810D03*
Y1306810D03*
Y1330810D03*
Y1336810D03*
Y1324810D03*
Y1318810D03*
Y1346065D03*
X101626Y1397635D03*
X106962Y1434041D03*
X106921Y1419492D03*
X106763Y1444599D03*
X107006Y1452651D03*
X107355Y1770437D03*
X107220Y1791589D03*
X107373Y1780544D03*
X106819Y1802230D03*
X144878Y1738861D03*
X157558Y51426D03*
X156865Y401207D03*
X156610Y751063D03*
X156854Y1101031D03*
X158618Y1399448D03*
X164037Y1400226D03*
X170351Y1401324D03*
X159192Y1451105D03*
X150309Y1737009D03*
X168151Y1739208D03*
X156183Y1735240D03*
X165782Y1732903D03*
X163257Y1737619D03*
X156452Y1800821D03*
X175989Y944537D03*
X176011Y936829D03*
X175359Y963486D03*
X175561Y955964D03*
X175135Y972490D03*
X175022Y980281D03*
X175742Y989958D03*
X175449Y997660D03*
X175698Y1008730D03*
X175473Y1016296D03*
X175448Y1031766D03*
X175897Y1023997D03*
X176083Y1402321D03*
X173394Y1736051D03*
X256947Y128276D03*
X257125Y115559D03*
X265722Y463102D03*
X265737Y473680D03*
X255837Y823626D03*
X255687Y812192D03*
X283086Y162675D03*
X271547Y245353D03*
X281193Y241624D03*
X281074Y337688D03*
X289895D03*
X291002Y417844D03*
X281569Y421169D03*
X278405Y512341D03*
X269516D03*
X285348Y595540D03*
X270109Y687192D03*
X278955D03*
X273114Y770968D03*
X282737Y767643D03*
X272181Y862354D03*
X281305Y862237D03*
X275966Y944767D03*
X285874Y941442D03*
X281124Y1031162D03*
X290107D03*
X282958Y1119471D03*
X289082Y1206777D03*
X279559D03*
X283808Y1293959D03*
X279518Y1389543D03*
X270579Y1389626D03*
X270234Y1467760D03*
X279990Y1464435D03*
X285054Y1558211D03*
X284086Y1644883D03*
X274704Y1738196D03*
X284583Y1738465D03*
X281066Y1819569D03*
X291550Y1814846D03*
X280240Y1858668D03*
X279976Y1864565D03*
X282717Y1913327D03*
X273817D03*
X304151Y63778D03*
X313089D03*
X294483Y67732D03*
X291943Y162630D03*
X308057Y248863D03*
X306267Y241010D03*
X314914Y238162D03*
X314940Y252083D03*
X305867Y258589D03*
X295509Y592215D03*
X309678Y1053262D03*
X292698Y1116146D03*
X312527Y1162266D03*
X312698Y1172804D03*
X294133Y1290634D03*
X314183Y1403423D03*
X302267Y1524401D03*
X301734Y1513883D03*
X312077Y1575871D03*
X294392Y1558211D03*
X294090Y1641558D03*
X311539Y1753499D03*
X314562Y1994087D03*
X331403Y51409D03*
X333889Y56021D03*
X338227Y61559D03*
X322005Y63778D03*
X320372Y225979D03*
X318088Y231820D03*
X321899Y238137D03*
X329930Y245684D03*
X331046Y232021D03*
X320961Y250105D03*
X324709Y231580D03*
X335522Y404033D03*
X323313Y418313D03*
X326196Y413982D03*
X328950Y409216D03*
X320980Y423225D03*
X336617Y577978D03*
X319305Y582111D03*
X329636Y584715D03*
X317724Y588250D03*
X337387Y586230D03*
X320380Y576491D03*
X331867Y589810D03*
X333750Y595326D03*
X323751Y589155D03*
X319852Y593330D03*
X321742Y599041D03*
X331568Y752967D03*
X339012Y752859D03*
X329336Y762693D03*
X334010Y758588D03*
X327524Y758020D03*
X339615Y926357D03*
X329938Y948756D03*
X332527Y943746D03*
X324098Y946104D03*
X318557Y941178D03*
X323868Y929978D03*
X326646Y939788D03*
X333300Y928464D03*
X336160Y937262D03*
X328583Y933262D03*
X321425Y951577D03*
X324246Y1051786D03*
X335677Y1048904D03*
X317592Y1053050D03*
X331920Y1116088D03*
X337509Y1109598D03*
X328989Y1121090D03*
X326558Y1126368D03*
X327452Y1279447D03*
X321978Y1282086D03*
X338047Y1282599D03*
X333242Y1276809D03*
X329619Y1284016D03*
X327932Y1289221D03*
X319404Y1401346D03*
X325636Y1399114D03*
X334646Y1400804D03*
X323720Y1570924D03*
X329399Y1571939D03*
X317243Y1574832D03*
X333474Y1566686D03*
X335963Y1573797D03*
X329887Y1752081D03*
X321283Y1753466D03*
X335730Y1753270D03*
X338309Y1927623D03*
X332399Y1926787D03*
X324803Y1990272D03*
X359931Y52189D03*
X348289Y50863D03*
X345089Y56190D03*
X340373Y51579D03*
X342097Y401684D03*
X363825Y401768D03*
X342900Y580126D03*
X362577Y752783D03*
X344109Y751809D03*
X343656Y933725D03*
X345578Y1047844D03*
X344099Y1106798D03*
X349855Y1104302D03*
X344130Y1401670D03*
X350690Y1403243D03*
X348710Y1570187D03*
X361011Y1568890D03*
X343402Y1572080D03*
X348245Y1575241D03*
X355364Y1570990D03*
X345537Y1916558D03*
X344402Y1911123D03*
X363361Y1918313D03*
X358318Y1920680D03*
X363411Y1923459D03*
X340336Y1922409D03*
X347676Y1922165D03*
X372204Y56126D03*
X365720Y52336D03*
X379257Y52158D03*
X379572Y58441D03*
X387524Y76847D03*
X374442Y406857D03*
X380619Y410112D03*
X380878Y403999D03*
X374542Y401282D03*
X368907Y404308D03*
X376654Y754748D03*
X382892Y767710D03*
X386790Y774338D03*
X380186Y761742D03*
X379335Y1189778D03*
X383276Y1184136D03*
X386816Y1179841D03*
X376472Y1194999D03*
X373674Y1199967D03*
X371523Y1204725D03*
X367829Y1566108D03*
X374775Y1919243D03*
X379403Y1917261D03*
X369748Y1921795D03*
X391278Y765894D03*
G54D19*
X45056Y1817693D03*
M02*
